(kicad_pcb
	(version 20260206)
	(generator "pcbnew")
	(generator_version "10.0")
	(general
		(thickness 1.6)
		(legacy_teardrops no)
	)
	(paper "A4")
	(title_block
		(title "baseboard — 13948-1b.1110WZS1818.brd")
		(comment 1 "Honey Badger (Wiwynn) / footprints 1793-1799 of 2523")
	)
	(layers
		(0 "F.Cu" signal "TOP")
		(4 "In1.Cu" signal "L2GND")
		(6 "In2.Cu" signal "L3")
		(8 "In3.Cu" signal "L4VCC")
		(10 "In4.Cu" signal "L5VCC")
		(12 "In5.Cu" signal "L6")
		(14 "In6.Cu" signal "L7GND")
		(2 "B.Cu" signal "BOTTOM")
		(9 "F.Adhes" user "F.Adhesive")
		(11 "B.Adhes" user "B.Adhesive")
		(13 "F.Paste" user "Package Geometry/Pastemask Top")
		(15 "B.Paste" user "Package Geometry/Pastemask Bottom")
		(5 "F.SilkS" user "Ref Des/Silkscreen Top")
		(7 "B.SilkS" user "Ref Des/Silkscreen Bottom")
		(1 "F.Mask" user "Board Geometry/Soldermask Top")
		(3 "B.Mask" user "Board Geometry/Soldermask Bottom")
		(17 "Dwgs.User" user "User.Drawings")
		(19 "Cmts.User" user "User.Comments")
		(21 "Eco1.User" user "User.Eco1")
		(23 "Eco2.User" user "User.Eco2")
		(25 "Edge.Cuts" user "Board Geometry/Outline")
		(27 "Margin" user)
		(31 "F.CrtYd" user "Package Geometry/Place Bound Top")
		(29 "B.CrtYd" user "Package Geometry/Place Bound Bottom")
		(35 "F.Fab" user "Ref Des/Assembly Top")
		(33 "B.Fab" user "Ref Des/Assembly Bottom")
	)
	(footprint ""
		(layer "B.Cu")
		(at 24.596344 -175.387762 90)
		(property "Reference" "SC1113"
			(at 0 0 90)
			(layer "B.SilkS")
			(hide yes)
			(effects
				(font
					(size 1.27 1.27)
				)
				(justify mirror)
			)
		)
		(property "Value" "SCD1U16V2KX-3GP"
			(at -1.1811 -2.7051 90)
			(unlocked yes)
			(layer "B.Fab")
			(hide yes)
			(effects
				(font
					(size 1.016 1.016)
					(thickness 0.1524)
				)
				(justify mirror)
			)
		)
		(property "Device Type" "C402H22"
			(at -1.1811 -4.2291 90)
			(unlocked yes)
			(layer "B.Fab")
			(hide yes)
			(effects
				(font
					(size 1.016 1.016)
					(thickness 0.1524)
				)
				(justify mirror)
			)
		)
		(duplicate_pad_numbers_are_jumpers no)
		(fp_rect
			(start 0.4318 0.9525)
			(end -0.4318 -0.9525)
			(stroke
				(width 0)
				(type default)
			)
			(fill no)
			(layer "B.CrtYd")
		)
		(fp_rect
			(start 0.4318 0.9525)
			(end -0.4318 -0.9525)
			(stroke
				(width 0)
				(type default)
			)
			(fill no)
			(layer "B.Fab")
		)
		(pad "1" smd custom
			(at 0 -0.4445 270)
			(size 0.1524 0.1524)
			(layers "B.Cu" "B.Mask" "B.Paste")
			(net "P3V3_STBY")
			(options
				(clearance outline)
				(anchor circle)
			)
			(primitives
				(gr_poly
					(pts
						(arc
							(start 0.3048 0.2032)
							(mid 0.275042 0.275042)
							(end 0.2032 0.3048)
						)
						(arc
							(start -0.2032 0.3048)
							(mid -0.275042 0.275042)
							(end -0.3048 0.2032)
						)
						(arc
							(start -0.3048 -0.2032)
							(mid -0.275042 -0.275042)
							(end -0.2032 -0.3048)
						)
						(arc
							(start 0.2032 -0.3048)
							(mid 0.275042 -0.275042)
							(end 0.3048 -0.2032)
						)
					)
					(width 0)
					(fill yes)
				)
			)
		)
		(pad "2" smd custom
			(at 0 0.4445 270)
			(size 0.1524 0.1524)
			(layers "B.Cu" "B.Mask" "B.Paste")
			(net "GND")
			(options
				(clearance outline)
				(anchor circle)
			)
			(primitives
				(gr_poly
					(pts
						(arc
							(start 0.3048 0.2032)
							(mid 0.275042 0.275042)
							(end 0.2032 0.3048)
						)
						(arc
							(start -0.2032 0.3048)
							(mid -0.275042 0.275042)
							(end -0.3048 0.2032)
						)
						(arc
							(start -0.3048 -0.2032)
							(mid -0.275042 -0.275042)
							(end -0.2032 -0.3048)
						)
						(arc
							(start 0.2032 -0.3048)
							(mid 0.275042 -0.275042)
							(end 0.3048 -0.2032)
						)
					)
					(width 0)
					(fill yes)
				)
			)
		)
	)
	(footprint ""
		(layer "B.Cu")
		(at 115.27917 -98.3742)
		(property "Reference" "SC1260"
			(at 0 0 0)
			(layer "B.SilkS")
			(hide yes)
			(effects
				(font
					(size 1.27 1.27)
				)
				(justify mirror)
			)
		)
		(property "Value" "SCD1U6D3V1KX-GP"
			(at 2.8321 -1.7399 0)
			(unlocked yes)
			(layer "B.Fab")
			(hide yes)
			(effects
				(font
					(size 1.016 1.016)
					(thickness 0.1524)
				)
				(justify mirror)
			)
		)
		(property "Device Type" "C0201H13"
			(at 2.8321 -3.2639 0)
			(unlocked yes)
			(layer "B.Fab")
			(hide yes)
			(effects
				(font
					(size 1.016 1.016)
					(thickness 0.1524)
				)
				(justify mirror)
			)
		)
		(duplicate_pad_numbers_are_jumpers no)
		(fp_rect
			(start 0.2794 0.6477)
			(end -0.2794 -0.6477)
			(stroke
				(width 0)
				(type default)
			)
			(fill no)
			(layer "B.CrtYd")
		)
		(fp_rect
			(start 0.2794 0.6477)
			(end -0.2794 -0.6477)
			(stroke
				(width 0)
				(type default)
			)
			(fill no)
			(layer "B.Fab")
		)
		(pad "1" smd custom
			(at 0 -0.2794 180)
			(size 0.0762 0.0762)
			(layers "B.Cu" "B.Mask" "B.Paste")
			(net "P0V9_E")
			(options
				(clearance outline)
				(anchor circle)
			)
			(primitives
				(gr_poly
					(pts
						(arc
							(start 0.1524 0.127)
							(mid 0.137521 0.162921)
							(end 0.1016 0.1778)
						)
						(arc
							(start -0.1016 0.1778)
							(mid -0.137521 0.162921)
							(end -0.1524 0.127)
						)
						(arc
							(start -0.1524 -0.127)
							(mid -0.137521 -0.162921)
							(end -0.1016 -0.1778)
						)
						(arc
							(start 0.1016 -0.1778)
							(mid 0.137521 -0.162921)
							(end 0.1524 -0.127)
						)
					)
					(width 0)
					(fill yes)
				)
			)
		)
		(pad "2" smd custom
			(at 0 0.2794 180)
			(size 0.0762 0.0762)
			(layers "B.Cu" "B.Mask" "B.Paste")
			(net "GND")
			(options
				(clearance outline)
				(anchor circle)
			)
			(primitives
				(gr_poly
					(pts
						(arc
							(start 0.1524 0.127)
							(mid 0.137521 0.162921)
							(end 0.1016 0.1778)
						)
						(arc
							(start -0.1016 0.1778)
							(mid -0.137521 0.162921)
							(end -0.1524 0.127)
						)
						(arc
							(start -0.1524 -0.127)
							(mid -0.137521 -0.162921)
							(end -0.1016 -0.1778)
						)
						(arc
							(start 0.1016 -0.1778)
							(mid 0.137521 -0.162921)
							(end 0.1524 -0.127)
						)
					)
					(width 0)
					(fill yes)
				)
			)
		)
	)
	(footprint ""
		(layer "B.Cu")
		(at 274.447 -187.071 90)
		(property "Reference" "R370"
			(at 0 0 90)
			(layer "B.SilkS")
			(hide yes)
			(effects
				(font
					(size 1.27 1.27)
				)
				(justify mirror)
			)
		)
		(property "Value" "3K3R2F-2-GP"
			(at -0.064008 -3.993896 90)
			(unlocked yes)
			(layer "B.Fab")
			(hide yes)
			(effects
				(font
					(size 1.016 1.016)
					(thickness 0.1524)
				)
				(justify mirror)
			)
		)
		(property "Device Type" "R402H16"
			(at -0.064008 -5.517896 90)
			(unlocked yes)
			(layer "B.Fab")
			(hide yes)
			(effects
				(font
					(size 1.016 1.016)
					(thickness 0.1524)
				)
				(justify mirror)
			)
		)
		(duplicate_pad_numbers_are_jumpers no)
		(fp_line
			(start 0.508 -0.9398)
			(end 0.508 0.9398)
			(stroke
				(width 0.1524)
				(type default)
			)
			(layer "B.SilkS")
		)
		(fp_line
			(start -0.508 -0.9398)
			(end 0.508 -0.9398)
			(stroke
				(width 0.1524)
				(type default)
			)
			(layer "B.SilkS")
		)
		(fp_rect
			(start 0.508 0.9398)
			(end -0.508 -0.9398)
			(stroke
				(width 0)
				(type default)
			)
			(fill no)
			(layer "B.CrtYd")
		)
		(fp_rect
			(start 0.508 0.9398)
			(end -0.508 -0.9398)
			(stroke
				(width 0)
				(type default)
			)
			(fill no)
			(layer "B.Fab")
		)
		(pad "1" smd custom
			(at 0 -0.4445 270)
			(size 0.1397 0.1397)
			(layers "B.Cu" "B.Mask" "B.Paste")
			(net "P3V3_STBY")
			(options
				(clearance outline)
				(anchor circle)
			)
			(primitives
				(gr_poly
					(pts
						(arc
							(start -0.1778 0.2794)
							(mid -0.249642 0.249642)
							(end -0.2794 0.1778)
						)
						(arc
							(start -0.2794 -0.1778)
							(mid -0.249642 -0.249642)
							(end -0.1778 -0.2794)
						)
						(arc
							(start 0.1778 -0.2794)
							(mid 0.249642 -0.249642)
							(end 0.2794 -0.1778)
						)
						(arc
							(start 0.2794 0.1778)
							(mid 0.249642 0.249642)
							(end 0.1778 0.2794)
						)
					)
					(width 0)
					(fill yes)
				)
			)
		)
		(pad "2" smd custom
			(at 0 0.4445 270)
			(size 0.1397 0.1397)
			(layers "B.Cu" "B.Mask" "B.Paste")
			(net "ROMD7")
			(options
				(clearance outline)
				(anchor circle)
			)
			(primitives
				(gr_poly
					(pts
						(arc
							(start -0.1778 0.2794)
							(mid -0.249642 0.249642)
							(end -0.2794 0.1778)
						)
						(arc
							(start -0.2794 -0.1778)
							(mid -0.249642 -0.249642)
							(end -0.1778 -0.2794)
						)
						(arc
							(start 0.1778 -0.2794)
							(mid 0.249642 -0.249642)
							(end 0.2794 -0.1778)
						)
						(arc
							(start 0.2794 0.1778)
							(mid 0.249642 0.249642)
							(end 0.1778 0.2794)
						)
					)
					(width 0)
					(fill yes)
				)
			)
		)
	)
	(footprint ""
		(layer "B.Cu")
		(at 287.3502 -204.978 180)
		(property "Reference" "C198"
			(at 0 0 0)
			(layer "B.SilkS")
			(hide yes)
			(effects
				(font
					(size 1.27 1.27)
				)
				(justify mirror)
			)
		)
		(property "Value" "SC1U10V3KX-4GP-U"
			(at 0 -2.8194 180)
			(unlocked yes)
			(layer "B.Fab")
			(hide yes)
			(effects
				(font
					(size 1.016 1.016)
					(thickness 0.1524)
				)
				(justify mirror)
			)
		)
		(property "Device Type" "C603H36"
			(at 0 -4.3434 180)
			(unlocked yes)
			(layer "B.Fab")
			(hide yes)
			(effects
				(font
					(size 1.016 1.016)
					(thickness 0.1524)
				)
				(justify mirror)
			)
		)
		(duplicate_pad_numbers_are_jumpers no)
		(fp_line
			(start -0.508 0)
			(end 0.508 0)
			(stroke
				(width 0.2032)
				(type default)
			)
			(layer "B.SilkS")
		)
		(fp_rect
			(start 0.5842 1.3335)
			(end -0.5842 -1.3335)
			(stroke
				(width 0)
				(type default)
			)
			(fill no)
			(layer "B.CrtYd")
		)
		(fp_rect
			(start 0.5842 1.3335)
			(end -0.5842 -1.3335)
			(stroke
				(width 0)
				(type default)
			)
			(fill no)
			(layer "B.Fab")
		)
		(pad "1" smd custom
			(at 0 -0.762)
			(size 0.2159 0.2159)
			(layers "B.Cu" "B.Mask" "B.Paste")
			(net "P1V53_STBY")
			(options
				(clearance outline)
				(anchor circle)
			)
			(primitives
				(gr_poly
					(pts
						(arc
							(start -0.3302 0.4318)
							(mid -0.402042 0.402042)
							(end -0.4318 0.3302)
						)
						(arc
							(start -0.4318 -0.3302)
							(mid -0.402042 -0.402042)
							(end -0.3302 -0.4318)
						)
						(arc
							(start 0.3302 -0.4318)
							(mid 0.402042 -0.402042)
							(end 0.4318 -0.3302)
						)
						(arc
							(start 0.4318 0.3302)
							(mid 0.402042 0.402042)
							(end 0.3302 0.4318)
						)
					)
					(width 0)
					(fill yes)
				)
			)
		)
		(pad "2" smd custom
			(at 0 0.762)
			(size 0.2159 0.2159)
			(layers "B.Cu" "B.Mask" "B.Paste")
			(net "GND")
			(options
				(clearance outline)
				(anchor circle)
			)
			(primitives
				(gr_poly
					(pts
						(arc
							(start -0.3302 0.4318)
							(mid -0.402042 0.402042)
							(end -0.4318 0.3302)
						)
						(arc
							(start -0.4318 -0.3302)
							(mid -0.402042 -0.402042)
							(end -0.3302 -0.4318)
						)
						(arc
							(start 0.3302 -0.4318)
							(mid 0.402042 -0.402042)
							(end 0.4318 -0.3302)
						)
						(arc
							(start 0.4318 0.3302)
							(mid 0.402042 0.402042)
							(end 0.3302 0.4318)
						)
					)
					(width 0)
					(fill yes)
				)
			)
		)
	)
	(footprint ""
		(layer "B.Cu")
		(at 323.342 -179.705 180)
		(property "Reference" "R5770"
			(at 0 0 0)
			(layer "B.SilkS")
			(hide yes)
			(effects
				(font
					(size 1.27 1.27)
				)
				(justify mirror)
			)
		)
		(property "Value" "1KR2F-3-GP"
			(at -0.064008 -3.993896 180)
			(unlocked yes)
			(layer "B.Fab")
			(hide yes)
			(effects
				(font
					(size 1.016 1.016)
					(thickness 0.1524)
				)
				(justify mirror)
			)
		)
		(property "Device Type" "R402H16"
			(at -0.064008 -5.517896 180)
			(unlocked yes)
			(layer "B.Fab")
			(hide yes)
			(effects
				(font
					(size 1.016 1.016)
					(thickness 0.1524)
				)
				(justify mirror)
			)
		)
		(duplicate_pad_numbers_are_jumpers no)
		(fp_line
			(start 0.508 -0.9398)
			(end 0.508 0.9398)
			(stroke
				(width 0.1524)
				(type default)
			)
			(layer "B.SilkS")
		)
		(fp_line
			(start -0.508 -0.9398)
			(end 0.508 -0.9398)
			(stroke
				(width 0.1524)
				(type default)
			)
			(layer "B.SilkS")
		)
		(fp_rect
			(start 0.508 0.9398)
			(end -0.508 -0.9398)
			(stroke
				(width 0)
				(type default)
			)
			(fill no)
			(layer "B.CrtYd")
		)
		(fp_rect
			(start 0.508 0.9398)
			(end -0.508 -0.9398)
			(stroke
				(width 0)
				(type default)
			)
			(fill no)
			(layer "B.Fab")
		)
		(pad "1" smd custom
			(at 0 -0.4445)
			(size 0.1397 0.1397)
			(layers "B.Cu" "B.Mask" "B.Paste")
			(net "ADC_P3V3_STBY")
			(options
				(clearance outline)
				(anchor circle)
			)
			(primitives
				(gr_poly
					(pts
						(arc
							(start -0.1778 0.2794)
							(mid -0.249642 0.249642)
							(end -0.2794 0.1778)
						)
						(arc
							(start -0.2794 -0.1778)
							(mid -0.249642 -0.249642)
							(end -0.1778 -0.2794)
						)
						(arc
							(start 0.1778 -0.2794)
							(mid 0.249642 -0.249642)
							(end 0.2794 -0.1778)
						)
						(arc
							(start 0.2794 0.1778)
							(mid 0.249642 0.249642)
							(end 0.1778 0.2794)
						)
					)
					(width 0)
					(fill yes)
				)
			)
		)
		(pad "2" smd custom
			(at 0 0.4445)
			(size 0.1397 0.1397)
			(layers "B.Cu" "B.Mask" "B.Paste")
			(net "GND")
			(options
				(clearance outline)
				(anchor circle)
			)
			(primitives
				(gr_poly
					(pts
						(arc
							(start -0.1778 0.2794)
							(mid -0.249642 0.249642)
							(end -0.2794 0.1778)
						)
						(arc
							(start -0.2794 -0.1778)
							(mid -0.249642 -0.249642)
							(end -0.1778 -0.2794)
						)
						(arc
							(start 0.1778 -0.2794)
							(mid 0.249642 -0.249642)
							(end 0.2794 -0.1778)
						)
						(arc
							(start 0.2794 0.1778)
							(mid 0.249642 0.249642)
							(end 0.1778 0.2794)
						)
					)
					(width 0)
					(fill yes)
				)
			)
		)
	)
	(footprint ""
		(layer "B.Cu")
		(at 111.195612 -221.996)
		(property "Reference" "SR903"
			(at 0 0 0)
			(layer "B.SilkS")
			(hide yes)
			(effects
				(font
					(size 1.27 1.27)
				)
				(justify mirror)
			)
		)
		(property "Value" "0R2J-2-GP"
			(at -0.064008 -3.993896 0)
			(unlocked yes)
			(layer "B.Fab")
			(hide yes)
			(effects
				(font
					(size 1.016 1.016)
					(thickness 0.1524)
				)
				(justify mirror)
			)
		)
		(property "Device Type" "R402H16"
			(at -0.064008 -5.517896 0)
			(unlocked yes)
			(layer "B.Fab")
			(hide yes)
			(effects
				(font
					(size 1.016 1.016)
					(thickness 0.1524)
				)
				(justify mirror)
			)
		)
		(duplicate_pad_numbers_are_jumpers no)
		(fp_line
			(start -0.508 -0.9398)
			(end 0.508 -0.9398)
			(stroke
				(width 0.1524)
				(type default)
			)
			(layer "B.SilkS")
		)
		(fp_line
			(start 0.508 -0.9398)
			(end 0.508 0.9398)
			(stroke
				(width 0.1524)
				(type default)
			)
			(layer "B.SilkS")
		)
		(fp_rect
			(start 0.508 0.9398)
			(end -0.508 -0.9398)
			(stroke
				(width 0)
				(type default)
			)
			(fill no)
			(layer "B.CrtYd")
		)
		(fp_rect
			(start 0.508 0.9398)
			(end -0.508 -0.9398)
			(stroke
				(width 0)
				(type default)
			)
			(fill no)
			(layer "B.Fab")
		)
		(pad "1" smd custom
			(at 0 -0.4445 180)
			(size 0.1397 0.1397)
			(layers "B.Cu" "B.Mask" "B.Paste")
			(net "SAS_GF_EXP_RX_DP8")
			(options
				(clearance outline)
				(anchor circle)
			)
			(primitives
				(gr_poly
					(pts
						(arc
							(start -0.1778 0.2794)
							(mid -0.249642 0.249642)
							(end -0.2794 0.1778)
						)
						(arc
							(start -0.2794 -0.1778)
							(mid -0.249642 -0.249642)
							(end -0.1778 -0.2794)
						)
						(arc
							(start 0.1778 -0.2794)
							(mid 0.249642 -0.249642)
							(end 0.2794 -0.1778)
						)
						(arc
							(start 0.2794 0.1778)
							(mid 0.249642 0.249642)
							(end 0.1778 0.2794)
						)
					)
					(width 0)
					(fill yes)
				)
			)
		)
		(pad "2" smd custom
			(at 0 0.4445 180)
			(size 0.1397 0.1397)
			(layers "B.Cu" "B.Mask" "B.Paste")
			(net "SAS_HDD_CONN_SER_RX8_P")
			(options
				(clearance outline)
				(anchor circle)
			)
			(primitives
				(gr_poly
					(pts
						(arc
							(start -0.1778 0.2794)
							(mid -0.249642 0.249642)
							(end -0.2794 0.1778)
						)
						(arc
							(start -0.2794 -0.1778)
							(mid -0.249642 -0.249642)
							(end -0.1778 -0.2794)
						)
						(arc
							(start 0.1778 -0.2794)
							(mid 0.249642 -0.249642)
							(end 0.2794 -0.1778)
						)
						(arc
							(start 0.2794 0.1778)
							(mid 0.249642 0.249642)
							(end 0.1778 0.2794)
						)
					)
					(width 0)
					(fill yes)
				)
			)
		)
	)
	(footprint ""
		(layer "B.Cu")
		(at 14.471904 -100.400866)
		(property "Reference" "C133"
			(at 0 0 0)
			(layer "B.SilkS")
			(hide yes)
			(effects
				(font
					(size 1.27 1.27)
				)
				(justify mirror)
			)
		)
		(property "Value" "SCD01U50V2KX-1GP"
			(at -1.1811 -2.7051 0)
			(unlocked yes)
			(layer "B.Fab")
			(hide yes)
			(effects
				(font
					(size 1.016 1.016)
					(thickness 0.1524)
				)
				(justify mirror)
			)
		)
		(property "Device Type" "C402H22"
			(at -1.1811 -4.2291 0)
			(unlocked yes)
			(layer "B.Fab")
			(hide yes)
			(effects
				(font
					(size 1.016 1.016)
					(thickness 0.1524)
				)
				(justify mirror)
			)
		)
		(duplicate_pad_numbers_are_jumpers no)
		(fp_rect
			(start 0.4318 0.9525)
			(end -0.4318 -0.9525)
			(stroke
				(width 0)
				(type default)
			)
			(fill no)
			(layer "B.CrtYd")
		)
		(fp_rect
			(start 0.4318 0.9525)
			(end -0.4318 -0.9525)
			(stroke
				(width 0)
				(type default)
			)
			(fill no)
			(layer "B.Fab")
		)
		(pad "1" smd custom
			(at 0 -0.4445 180)
			(size 0.1524 0.1524)
			(layers "B.Cu" "B.Mask" "B.Paste")
			(net "IOC_SAS_RX_N5")
			(options
				(clearance outline)
				(anchor circle)
			)
			(primitives
				(gr_poly
					(pts
						(arc
							(start 0.3048 0.2032)
							(mid 0.275042 0.275042)
							(end 0.2032 0.3048)
						)
						(arc
							(start -0.2032 0.3048)
							(mid -0.275042 0.275042)
							(end -0.3048 0.2032)
						)
						(arc
							(start -0.3048 -0.2032)
							(mid -0.275042 -0.275042)
							(end -0.2032 -0.3048)
						)
						(arc
							(start 0.2032 -0.3048)
							(mid 0.275042 -0.275042)
							(end 0.3048 -0.2032)
						)
					)
					(width 0)
					(fill yes)
				)
			)
		)
		(pad "2" smd custom
			(at 0 0.4445 180)
			(size 0.1524 0.1524)
			(layers "B.Cu" "B.Mask" "B.Paste")
			(net "SAS_EXT_CONN_RX17_N")
			(options
				(clearance outline)
				(anchor circle)
			)
			(primitives
				(gr_poly
					(pts
						(arc
							(start 0.3048 0.2032)
							(mid 0.275042 0.275042)
							(end 0.2032 0.3048)
						)
						(arc
							(start -0.2032 0.3048)
							(mid -0.275042 0.275042)
							(end -0.3048 0.2032)
						)
						(arc
							(start -0.3048 -0.2032)
							(mid -0.275042 -0.275042)
							(end -0.2032 -0.3048)
						)
						(arc
							(start 0.2032 -0.3048)
							(mid 0.275042 -0.275042)
							(end 0.3048 -0.2032)
						)
					)
					(width 0)
					(fill yes)
				)
			)
		)
	)
)
